(kicad_pcb
	(version 20260206)
	(generator "pcbnew")
	(generator_version "10.0")
	(general
		(thickness 1.6)
		(legacy_teardrops no)
	)
	(paper "A4")
	(title_block
		(title "Wiwynn_Tioga_Pass_MB.brd")
		(comment 1 "Tioga Pass / footprints 2875-2881 of 4770")
	)
	(layers
		(0 "F.Cu" signal "TOP")
		(4 "In1.Cu" signal "L2GND")
		(6 "In2.Cu" signal "L3")
		(8 "In3.Cu" signal "L4GND")
		(10 "In4.Cu" signal "L5")
		(12 "In5.Cu" signal "L6GND")
		(14 "In6.Cu" signal "L7VCC")
		(16 "In7.Cu" signal "L8VCC")
		(18 "In8.Cu" signal "L9GND")
		(20 "In9.Cu" signal "L10")
		(22 "In10.Cu" signal "L11GND")
		(24 "In11.Cu" signal "L12")
		(26 "In12.Cu" signal "L13GND")
		(2 "B.Cu" signal "BOTTOM")
		(9 "F.Adhes" user "F.Adhesive")
		(11 "B.Adhes" user "B.Adhesive")
		(13 "F.Paste" user "Package Geometry/Pastemask Top")
		(15 "B.Paste" user "Package Geometry/Pastemask Bottom")
		(5 "F.SilkS" user "Ref Des/Silkscreen Top")
		(7 "B.SilkS" user "Ref Des/Silkscreen Bottom")
		(1 "F.Mask" user "Board Geometry/Soldermask Top")
		(3 "B.Mask" user "Board Geometry/Soldermask Bottom")
		(17 "Dwgs.User" user "User.Drawings")
		(19 "Cmts.User" user "User.Comments")
		(21 "Eco1.User" user "User.Eco1")
		(23 "Eco2.User" user "User.Eco2")
		(25 "Edge.Cuts" user "Board Geometry/Outline")
		(27 "Margin" user)
		(31 "F.CrtYd" user "Package Geometry/Place Bound Top")
		(29 "B.CrtYd" user "Package Geometry/Place Bound Bottom")
		(35 "F.Fab" user "Ref Des/Assembly Top")
		(33 "B.Fab" user "Ref Des/Assembly Bottom")
	)
	(footprint ""
		(layer "B.Cu")
		(at 482.9556 -38.4429 180)
		(property "Reference" "R1T32"
			(at 0 0 0)
			(layer "B.SilkS")
			(hide yes)
			(effects
				(font
					(size 1.27 1.27)
				)
				(justify mirror)
			)
		)
		(property "Value" ""
			(at 0 0 0)
			(layer "B.Fab")
			(effects
				(font
					(size 1.27 1.27)
				)
				(justify mirror)
			)
		)
		(duplicate_pad_numbers_are_jumpers no)
		(fp_poly
			(pts
				(xy 0.4953 -0.2032) (xy -0.4953 -0.2032) (xy -0.4953 1.6002) (xy 0.4953 1.6002)
			)
			(stroke
				(width 0)
				(type default)
			)
			(fill no)
			(layer "B.CrtYd")
		)
		(fp_line
			(start 0.4953 1.6002)
			(end 0.4953 -0.2032)
			(stroke
				(width 0.1)
				(type default)
			)
			(layer "B.Fab")
		)
		(fp_line
			(start 0.4953 -0.2032)
			(end -0.4953 -0.2032)
			(stroke
				(width 0.1)
				(type default)
			)
			(layer "B.Fab")
		)
		(fp_line
			(start -0.4953 1.6002)
			(end 0.4953 1.6002)
			(stroke
				(width 0.1)
				(type default)
			)
			(layer "B.Fab")
		)
		(fp_line
			(start -0.4953 -0.2032)
			(end -0.4953 1.6002)
			(stroke
				(width 0.1)
				(type default)
			)
			(layer "B.Fab")
		)
		(pad "1" smd rect
			(at 0 0)
			(size 0.762 0.889)
			(layers "B.Cu" "B.Mask" "B.Paste")
			(net "P1V5_LAN")
		)
		(pad "2" smd rect
			(at 0 1.397)
			(size 0.762 0.889)
			(layers "B.Cu" "B.Mask" "B.Paste")
			(net "P1V5_LAN_I210")
		)
		(zone
			(layer "B.Cu")
			(hatch none 0.5)
			(connect_pads
				(clearance 0)
			)
			(min_thickness 0.25)
			(keepout
				(tracks not_allowed)
				(vias allowed)
				(pads allowed)
				(copperpour not_allowed)
				(footprints allowed)
			)
			(placement
				(enabled no)
				(sheetname "")
			)
			(fill
				(thermal_gap 0.5)
				(thermal_bridge_width 0.5)
				(island_removal_mode 0)
			)
			(polygon
				(pts
					(xy 482.5746 -39.3954) (xy 482.5746 -38.8874) (xy 483.3366 -38.8874) (xy 483.3366 -39.3954)
				)
			)
		)
		(zone
			(layer "B.Cu")
			(hatch none 0.5)
			(connect_pads
				(clearance 0)
			)
			(min_thickness 0.25)
			(keepout
				(tracks allowed)
				(vias not_allowed)
				(pads allowed)
				(copperpour not_allowed)
				(footprints allowed)
			)
			(placement
				(enabled no)
				(sheetname "")
			)
			(fill
				(thermal_gap 0.5)
				(thermal_bridge_width 0.5)
				(island_removal_mode 0)
			)
			(polygon
				(pts
					(xy 483.3366 -39.3954) (xy 483.3366 -38.8874) (xy 482.5746 -38.8874) (xy 482.5746 -39.3954)
				)
			)
		)
	)
	(footprint ""
		(layer "B.Cu")
		(at 375.285 -56.6039)
		(property "Reference" "R8F6"
			(at 0 0 0)
			(layer "B.SilkS")
			(hide yes)
			(effects
				(font
					(size 1.27 1.27)
				)
				(justify mirror)
			)
		)
		(property "Value" ""
			(at 0 0 0)
			(layer "B.Fab")
			(effects
				(font
					(size 1.27 1.27)
				)
				(justify mirror)
			)
		)
		(duplicate_pad_numbers_are_jumpers no)
		(fp_poly
			(pts
				(xy 0.2794 -0.1016) (xy -0.2794 -0.1016) (xy -0.2794 0.9906) (xy 0.2794 0.9906)
			)
			(stroke
				(width 0)
				(type default)
			)
			(fill no)
			(layer "B.CrtYd")
		)
		(fp_line
			(start -0.2794 -0.1016)
			(end 0.2794 -0.1016)
			(stroke
				(width 0.1)
				(type default)
			)
			(layer "B.Fab")
		)
		(fp_line
			(start -0.2794 0.9906)
			(end -0.2794 -0.1016)
			(stroke
				(width 0.1)
				(type default)
			)
			(layer "B.Fab")
		)
		(fp_line
			(start 0.2794 -0.1016)
			(end 0.2794 0.9906)
			(stroke
				(width 0.1)
				(type default)
			)
			(layer "B.Fab")
		)
		(fp_line
			(start 0.2794 0.9906)
			(end -0.2794 0.9906)
			(stroke
				(width 0.1)
				(type default)
			)
			(layer "B.Fab")
		)
		(pad "1" smd rect
			(at 0 0 180)
			(size 0.508 0.508)
			(layers "B.Cu" "B.Mask" "B.Paste")
			(net "SPI_PCH_MISO")
		)
		(pad "2" smd rect
			(at 0 0.889 180)
			(size 0.508 0.508)
			(layers "B.Cu" "B.Mask" "B.Paste")
			(net "SPI_PCH_MISO_R")
		)
		(zone
			(layer "B.Cu")
			(hatch none 0.5)
			(connect_pads
				(clearance 0)
			)
			(min_thickness 0.25)
			(keepout
				(tracks allowed)
				(vias not_allowed)
				(pads allowed)
				(copperpour not_allowed)
				(footprints allowed)
			)
			(placement
				(enabled no)
				(sheetname "")
			)
			(fill
				(thermal_gap 0.5)
				(thermal_bridge_width 0.5)
				(island_removal_mode 0)
			)
			(polygon
				(pts
					(xy 375.539 -56.3499) (xy 375.031 -56.3499) (xy 375.031 -55.9689) (xy 375.539 -55.9689)
				)
			)
		)
		(zone
			(layer "B.Cu")
			(hatch none 0.5)
			(connect_pads
				(clearance 0)
			)
			(min_thickness 0.25)
			(keepout
				(tracks not_allowed)
				(vias allowed)
				(pads allowed)
				(copperpour not_allowed)
				(footprints allowed)
			)
			(placement
				(enabled no)
				(sheetname "")
			)
			(fill
				(thermal_gap 0.5)
				(thermal_bridge_width 0.5)
				(island_removal_mode 0)
			)
			(polygon
				(pts
					(xy 375.539 -55.9689) (xy 375.031 -55.9689) (xy 375.031 -56.3499) (xy 375.539 -56.3499)
				)
			)
		)
	)
	(footprint ""
		(layer "B.Cu")
		(at 28.0924 -8.122412 -90)
		(property "Reference" "C9U8"
			(at 0 0 90)
			(layer "B.SilkS")
			(hide yes)
			(effects
				(font
					(size 1.27 1.27)
				)
				(justify mirror)
			)
		)
		(property "Value" ""
			(at 0 0 90)
			(layer "B.Fab")
			(effects
				(font
					(size 1.27 1.27)
				)
				(justify mirror)
			)
		)
		(duplicate_pad_numbers_are_jumpers no)
		(fp_rect
			(start 0.7239 -0.2159)
			(end -0.7239 1.9939)
			(stroke
				(width 0)
				(type default)
			)
			(fill no)
			(layer "B.CrtYd")
		)
		(fp_line
			(start -0.7239 1.9939)
			(end -0.7239 -0.2159)
			(stroke
				(width 0.1)
				(type default)
			)
			(layer "B.Fab")
		)
		(fp_line
			(start 0.7239 1.9939)
			(end -0.7239 1.9939)
			(stroke
				(width 0.1)
				(type default)
			)
			(layer "B.Fab")
		)
		(fp_line
			(start -0.7239 -0.2159)
			(end 0.7239 -0.2159)
			(stroke
				(width 0.1)
				(type default)
			)
			(layer "B.Fab")
		)
		(fp_line
			(start 0.7239 -0.2159)
			(end 0.7239 1.9939)
			(stroke
				(width 0.1)
				(type default)
			)
			(layer "B.Fab")
		)
		(pad "1" smd rect
			(at 0 0 90)
			(size 1.27 1.016)
			(layers "B.Cu" "B.Mask" "B.Paste")
			(net "P12V_NVDIMM_GHJ")
		)
		(pad "2" smd rect
			(at 0 1.778 90)
			(size 1.27 1.016)
			(layers "B.Cu" "B.Mask" "B.Paste")
			(net "GND")
		)
		(zone
			(layer "B.Cu")
			(hatch none 0.5)
			(connect_pads
				(clearance 0)
			)
			(min_thickness 0.25)
			(keepout
				(tracks not_allowed)
				(vias allowed)
				(pads allowed)
				(copperpour not_allowed)
				(footprints allowed)
			)
			(placement
				(enabled no)
				(sheetname "")
			)
			(fill
				(thermal_gap 0.5)
				(thermal_bridge_width 0.5)
				(island_removal_mode 0)
			)
			(polygon
				(pts
					(xy 27.5844 -7.487412) (xy 27.5844 -8.757412) (xy 26.8224 -8.757412) (xy 26.8224 -7.487412)
				)
			)
		)
	)
	(footprint ""
		(layer "B.Cu")
		(at 195.453 -154.6352 90)
		(property "Reference" "C6L1"
			(at 0 0 90)
			(layer "B.SilkS")
			(hide yes)
			(effects
				(font
					(size 1.27 1.27)
				)
				(justify mirror)
			)
		)
		(property "Value" ""
			(at 0 0 90)
			(layer "B.Fab")
			(effects
				(font
					(size 1.27 1.27)
				)
				(justify mirror)
			)
		)
		(duplicate_pad_numbers_are_jumpers no)
		(fp_poly
			(pts
				(xy -0.3048 -0.1016) (xy -0.3048 0.9906) (xy 0.3048 0.9906) (xy 0.3048 -0.1016)
			)
			(stroke
				(width 0)
				(type default)
			)
			(fill no)
			(layer "B.CrtYd")
		)
		(fp_line
			(start 0.3048 -0.1016)
			(end 0.3048 0.9906)
			(stroke
				(width 0.1)
				(type default)
			)
			(layer "B.Fab")
		)
		(fp_line
			(start -0.3048 -0.1016)
			(end 0.3048 -0.1016)
			(stroke
				(width 0.1)
				(type default)
			)
			(layer "B.Fab")
		)
		(fp_line
			(start 0.3048 0.9906)
			(end -0.3048 0.9906)
			(stroke
				(width 0.1)
				(type default)
			)
			(layer "B.Fab")
		)
		(fp_line
			(start -0.3048 0.9906)
			(end -0.3048 -0.1016)
			(stroke
				(width 0.1)
				(type default)
			)
			(layer "B.Fab")
		)
		(pad "1" smd rect
			(at 0 0 270)
			(size 0.508 0.508)
			(layers "B.Cu" "B.Mask" "B.Paste")
			(net "M_F_VREF")
		)
		(pad "2" smd rect
			(at 0 0.889 270)
			(size 0.508 0.508)
			(layers "B.Cu" "B.Mask" "B.Paste")
			(net "GND")
		)
		(zone
			(layer "B.Cu")
			(hatch none 0.5)
			(connect_pads
				(clearance 0)
			)
			(min_thickness 0.25)
			(keepout
				(tracks allowed)
				(vias not_allowed)
				(pads allowed)
				(copperpour not_allowed)
				(footprints allowed)
			)
			(placement
				(enabled no)
				(sheetname "")
			)
			(fill
				(thermal_gap 0.5)
				(thermal_bridge_width 0.5)
				(island_removal_mode 0)
			)
			(polygon
				(pts
					(xy 195.707 -154.8892) (xy 195.707 -154.3812) (xy 196.088 -154.3812) (xy 196.088 -154.8892)
				)
			)
		)
		(zone
			(layer "B.Cu")
			(hatch none 0.5)
			(connect_pads
				(clearance 0)
			)
			(min_thickness 0.25)
			(keepout
				(tracks not_allowed)
				(vias allowed)
				(pads allowed)
				(copperpour not_allowed)
				(footprints allowed)
			)
			(placement
				(enabled no)
				(sheetname "")
			)
			(fill
				(thermal_gap 0.5)
				(thermal_bridge_width 0.5)
				(island_removal_mode 0)
			)
			(polygon
				(pts
					(xy 196.088 -154.8892) (xy 196.088 -154.3812) (xy 195.707 -154.3812) (xy 195.707 -154.8892)
				)
			)
		)
	)
	(footprint ""
		(layer "B.Cu")
		(at 258.318 -135.3312 -90)
		(property "Reference" "C5M9"
			(at 0 0 90)
			(layer "B.SilkS")
			(hide yes)
			(effects
				(font
					(size 1.27 1.27)
				)
				(justify mirror)
			)
		)
		(property "Value" ""
			(at 0 0 90)
			(layer "B.Fab")
			(effects
				(font
					(size 1.27 1.27)
				)
				(justify mirror)
			)
		)
		(duplicate_pad_numbers_are_jumpers no)
		(fp_rect
			(start 0.500126 1.598422)
			(end -0.500126 -0.201422)
			(stroke
				(width 0)
				(type default)
			)
			(fill no)
			(layer "B.CrtYd")
		)
		(fp_line
			(start -0.500126 1.598422)
			(end 0.500126 1.598422)
			(stroke
				(width 0.1)
				(type default)
			)
			(layer "B.Fab")
		)
		(fp_line
			(start 0.500126 1.598422)
			(end 0.500126 -0.201422)
			(stroke
				(width 0.1)
				(type default)
			)
			(layer "B.Fab")
		)
		(fp_line
			(start -0.500126 -0.201422)
			(end -0.500126 1.598422)
			(stroke
				(width 0.1)
				(type default)
			)
			(layer "B.Fab")
		)
		(fp_line
			(start 0.500126 -0.201422)
			(end -0.500126 -0.201422)
			(stroke
				(width 0.1)
				(type default)
			)
			(layer "B.Fab")
		)
		(pad "1" smd rect
			(at 0 0 180)
			(size 0.889 0.9906)
			(layers "B.Cu" "B.Mask" "B.Paste")
			(net "PVDDQ_DEF")
		)
		(pad "2" smd rect
			(at 0 1.397 180)
			(size 0.889 0.9906)
			(layers "B.Cu" "B.Mask" "B.Paste")
			(net "GND")
		)
		(zone
			(layer "B.Cu")
			(hatch none 0.5)
			(connect_pads
				(clearance 0)
			)
			(min_thickness 0.25)
			(keepout
				(tracks allowed)
				(vias not_allowed)
				(pads allowed)
				(copperpour not_allowed)
				(footprints allowed)
			)
			(placement
				(enabled no)
				(sheetname "")
			)
			(fill
				(thermal_gap 0.5)
				(thermal_bridge_width 0.5)
				(island_removal_mode 0)
			)
			(polygon
				(pts
					(xy 257.3655 -134.8359) (xy 257.8735 -134.8359) (xy 257.8735 -135.8265) (xy 257.3655 -135.8265)
				)
			)
		)
		(zone
			(layer "B.Cu")
			(hatch none 0.5)
			(connect_pads
				(clearance 0)
			)
			(min_thickness 0.25)
			(keepout
				(tracks not_allowed)
				(vias allowed)
				(pads allowed)
				(copperpour not_allowed)
				(footprints allowed)
			)
			(placement
				(enabled no)
				(sheetname "")
			)
			(fill
				(thermal_gap 0.5)
				(thermal_bridge_width 0.5)
				(island_removal_mode 0)
			)
			(polygon
				(pts
					(xy 257.3655 -134.8359) (xy 257.8735 -134.8359) (xy 257.8735 -135.8265) (xy 257.3655 -135.8265)
				)
			)
		)
	)
	(footprint ""
		(layer "B.Cu")
		(at 398.146778 -157.11297 -90)
		(property "Reference" "CF23"
			(at 0 0 90)
			(layer "B.SilkS")
			(hide yes)
			(effects
				(font
					(size 1.27 1.27)
				)
				(justify mirror)
			)
		)
		(property "Value" "*"
			(at -1.1811 -2.8194 270)
			(unlocked yes)
			(layer "B.Fab")
			(hide yes)
			(effects
				(font
					(size 1.27 1.016)
					(thickness 0.1524)
				)
				(justify mirror)
			)
		)
		(property "Device Type" "SC22P50V2JN-4GP_SMD-BCG-SC22P5A"
			(at -1.1811 -4.3434 270)
			(unlocked yes)
			(layer "B.Fab")
			(hide yes)
			(effects
				(font
					(size 1.27 1.016)
					(thickness 0.1524)
				)
				(justify mirror)
			)
		)
		(duplicate_pad_numbers_are_jumpers no)
		(fp_rect
			(start 0.4318 0.9525)
			(end -0.4318 -0.9525)
			(stroke
				(width 0)
				(type default)
			)
			(fill no)
			(layer "B.CrtYd")
		)
		(fp_rect
			(start 0.4318 0.9525)
			(end -0.4318 -0.9525)
			(stroke
				(width 0)
				(type default)
			)
			(fill no)
			(layer "B.Fab")
		)
		(pad "1" smd custom
			(at 0 -0.4445 90)
			(size 0.1524 0.1524)
			(layers "B.Cu" "B.Mask" "B.Paste")
			(net "VR_PVNN_PCH_AIREF1")
			(options
				(clearance outline)
				(anchor circle)
			)
			(primitives
				(gr_poly
					(pts
						(arc
							(start 0.3048 0.2032)
							(mid 0.275042 0.275042)
							(end 0.2032 0.3048)
						)
						(arc
							(start -0.2032 0.3048)
							(mid -0.275042 0.275042)
							(end -0.3048 0.2032)
						)
						(arc
							(start -0.3048 -0.2032)
							(mid -0.275042 -0.275042)
							(end -0.2032 -0.3048)
						)
						(arc
							(start 0.2032 -0.3048)
							(mid 0.275042 -0.275042)
							(end 0.3048 -0.2032)
						)
					)
					(width 0)
					(fill yes)
				)
			)
		)
		(pad "2" smd custom
			(at 0 0.4445 90)
			(size 0.1524 0.1524)
			(layers "B.Cu" "B.Mask" "B.Paste")
			(net "ISENSE_PVNN_PCH_PH1_IMON")
			(options
				(clearance outline)
				(anchor circle)
			)
			(primitives
				(gr_poly
					(pts
						(arc
							(start 0.3048 0.2032)
							(mid 0.275042 0.275042)
							(end 0.2032 0.3048)
						)
						(arc
							(start -0.2032 0.3048)
							(mid -0.275042 0.275042)
							(end -0.3048 0.2032)
						)
						(arc
							(start -0.3048 -0.2032)
							(mid -0.275042 -0.275042)
							(end -0.2032 -0.3048)
						)
						(arc
							(start 0.2032 -0.3048)
							(mid 0.275042 -0.275042)
							(end 0.3048 -0.2032)
						)
					)
					(width 0)
					(fill yes)
				)
			)
		)
	)
	(footprint ""
		(layer "B.Cu")
		(at 381.5842 -2.448814)
		(property "Reference" "C8W5"
			(at 0.8382 -0.67818 0)
			(unlocked yes)
			(layer "B.SilkS")
			(effects
				(font
					(size 0.4064 0.254)
					(thickness 0.1524)
				)
				(justify left mirror)
			)
		)
		(property "Value" ""
			(at 0 0 0)
			(layer "B.Fab")
			(effects
				(font
					(size 1.27 1.27)
				)
				(justify mirror)
			)
		)
		(duplicate_pad_numbers_are_jumpers no)
		(fp_poly
			(pts
				(xy -0.3048 -0.1016) (xy -0.3048 0.9906) (xy 0.3048 0.9906) (xy 0.3048 -0.1016)
			)
			(stroke
				(width 0)
				(type default)
			)
			(fill no)
			(layer "B.CrtYd")
		)
		(fp_line
			(start -0.3048 -0.1016)
			(end 0.3048 -0.1016)
			(stroke
				(width 0.1)
				(type default)
			)
			(layer "B.Fab")
		)
		(fp_line
			(start -0.3048 0.9906)
			(end -0.3048 -0.1016)
			(stroke
				(width 0.1)
				(type default)
			)
			(layer "B.Fab")
		)
		(fp_line
			(start 0.3048 -0.1016)
			(end 0.3048 0.9906)
			(stroke
				(width 0.1)
				(type default)
			)
			(layer "B.Fab")
		)
		(fp_line
			(start 0.3048 0.9906)
			(end -0.3048 0.9906)
			(stroke
				(width 0.1)
				(type default)
			)
			(layer "B.Fab")
		)
		(pad "1" smd rect
			(at 0 0 180)
			(size 0.508 0.508)
			(layers "B.Cu" "B.Mask" "B.Paste")
			(net "P3V3_STBY")
		)
		(pad "2" smd rect
			(at 0 0.889 180)
			(size 0.508 0.508)
			(layers "B.Cu" "B.Mask" "B.Paste")
			(net "GND")
		)
		(zone
			(layer "B.Cu")
			(hatch none 0.5)
			(connect_pads
				(clearance 0)
			)
			(min_thickness 0.25)
			(keepout
				(tracks allowed)
				(vias not_allowed)
				(pads allowed)
				(copperpour not_allowed)
				(footprints allowed)
			)
			(placement
				(enabled no)
				(sheetname "")
			)
			(fill
				(thermal_gap 0.5)
				(thermal_bridge_width 0.5)
				(island_removal_mode 0)
			)
			(polygon
				(pts
					(xy 381.8382 -2.194814) (xy 381.3302 -2.194814) (xy 381.3302 -1.813814) (xy 381.8382 -1.813814)
				)
			)
		)
		(zone
			(layer "B.Cu")
			(hatch none 0.5)
			(connect_pads
				(clearance 0)
			)
			(min_thickness 0.25)
			(keepout
				(tracks not_allowed)
				(vias allowed)
				(pads allowed)
				(copperpour not_allowed)
				(footprints allowed)
			)
			(placement
				(enabled no)
				(sheetname "")
			)
			(fill
				(thermal_gap 0.5)
				(thermal_bridge_width 0.5)
				(island_removal_mode 0)
			)
			(polygon
				(pts
					(xy 381.8382 -1.813814) (xy 381.3302 -1.813814) (xy 381.3302 -2.194814) (xy 381.8382 -2.194814)
				)
			)
		)
	)
)
